# S9S_MB_2U (Grand Teton) — schematic netlist excerpt (pin names and nets, part order shuffled) for the footprints in the layout excerpt that follows; sources: Cadence DE-HDL packaged netlist, KiCad conversion of 03242023_DA0F0TMBIJ0_F0T_Motherboard_J_brd_V01_OCP.brd

U224  74LVC1G126SE7  74LVC1G126SE-7 IC  pkg SOT353_0-65_2X1-25  page 154
  OE  = OCP_SFF_AUX_PWR_EN_R4
  A  = RST_SMB_SWITCH_N
  GND  = GND
  Y  = RST_HP_OCP_SFF_R_N
  VCC  = P3V3_AUX

C2273  Q_CAP  1000PF 50V 5% EMPTY  pkg 0402  page 145 : A = GPU_3V3IO_RSVD3_ISO ; B = GND

(kicad_pcb
	(version 20260206)
	(generator "pcbnew")
	(generator_version "10.0")
	(general
		(thickness 1.6)
		(legacy_teardrops no)
	)
	(paper "A4")
	(title_block
		(title "03242023_DA0F0TMBIJ0_F0T_Motherboard_J_brd_V01_OCP.brd")
		(comment 1 "Grand Teton / footprints 96-97 of 6105")
	)
	(layers
		(0 "F.Cu" signal "TOP")
		(4 "In1.Cu" signal "GND")
		(6 "In2.Cu" signal "IN1")
		(8 "In3.Cu" signal "GND1")
		(10 "In4.Cu" signal "IN2")
		(12 "In5.Cu" signal "GND2")
		(14 "In6.Cu" signal "IN3")
		(16 "In7.Cu" signal "GND3")
		(18 "In8.Cu" signal "VCC")
		(20 "In9.Cu" signal "VCC1")
		(22 "In10.Cu" signal "GND4")
		(24 "In11.Cu" signal "IN4")
		(26 "In12.Cu" signal "GND5")
		(28 "In13.Cu" signal "IN5")
		(30 "In14.Cu" signal "GND6")
		(32 "In15.Cu" signal "IN6")
		(34 "In16.Cu" signal "GND7")
		(2 "B.Cu" signal "BOTTOM")
		(9 "F.Adhes" user "F.Adhesive")
		(11 "B.Adhes" user "B.Adhesive")
		(13 "F.Paste" user "Package Geometry/Pastemask Top")
		(15 "B.Paste" user "Package Geometry/Pastemask Bottom")
		(5 "F.SilkS" user "Ref Des/Silkscreen Top")
		(7 "B.SilkS" user "Ref Des/Silkscreen Bottom")
		(1 "F.Mask" user "Board Geometry/Soldermask Top")
		(3 "B.Mask" user "Board Geometry/Soldermask Bottom")
		(17 "Dwgs.User" user "User.Drawings")
		(19 "Cmts.User" user "User.Comments")
		(21 "Eco1.User" user "User.Eco1")
		(23 "Eco2.User" user "User.Eco2")
		(25 "Edge.Cuts" user "Board Geometry/Outline")
		(27 "Margin" user)
		(31 "F.CrtYd" user "Package Geometry/Place Bound Top")
		(29 "B.CrtYd" user "Package Geometry/Place Bound Bottom")
		(35 "F.Fab" user "Ref Des/Assembly Top")
		(33 "B.Fab" user "Ref Des/Assembly Bottom")
	)
	(footprint ""
		(layer "F.Cu")
		(at 357.548942 -389.19277 180)
		(property "Reference" "C2273"
			(at 0 0 180)
			(layer "F.SilkS")
			(hide yes)
			(effects
				(font
					(size 1.27 1.27)
				)
			)
		)
		(property "Value" ""
			(at 0 0 180)
			(layer "F.Fab")
			(effects
				(font
					(size 1.27 1.27)
				)
			)
		)
		(duplicate_pad_numbers_are_jumpers no)
		(fp_line
			(start 0.7874 0.4064)
			(end -0.7874 0.4064)
			(stroke
				(width 0.1524)
				(type default)
			)
			(layer "F.SilkS")
		)
		(fp_line
			(start 0.7874 -0.4064)
			(end 0.7874 0.4064)
			(stroke
				(width 0.1524)
				(type default)
			)
			(layer "F.SilkS")
		)
		(fp_line
			(start -0.7874 0.4064)
			(end -0.7874 -0.4064)
			(stroke
				(width 0.1524)
				(type default)
			)
			(layer "F.SilkS")
		)
		(fp_line
			(start -0.7874 -0.4064)
			(end 0.7874 -0.4064)
			(stroke
				(width 0.1524)
				(type default)
			)
			(layer "F.SilkS")
		)
		(fp_line
			(start 0.67945 0.3048)
			(end 0.120396 0.3048)
			(stroke
				(width 0.1)
				(type default)
			)
			(layer "F.Fab")
		)
		(fp_line
			(start 0.67945 -0.3048)
			(end 0.67945 0.3048)
			(stroke
				(width 0.1)
				(type default)
			)
			(layer "F.Fab")
		)
		(fp_line
			(start 0.12065 -0.2794)
			(end 0.12065 -0.3048)
			(stroke
				(width 0.1)
				(type default)
			)
			(layer "F.Fab")
		)
		(fp_line
			(start 0.12065 -0.3048)
			(end 0.67945 -0.3048)
			(stroke
				(width 0.1)
				(type default)
			)
			(layer "F.Fab")
		)
		(fp_line
			(start 0.120396 0.3048)
			(end 0.120396 0.2794)
			(stroke
				(width 0.1)
				(type default)
			)
			(layer "F.Fab")
		)
		(fp_line
			(start 0.120396 0.2794)
			(end -0.12065 0.2794)
			(stroke
				(width 0.1)
				(type default)
			)
			(layer "F.Fab")
		)
		(fp_line
			(start -0.12065 0.3048)
			(end -0.67945 0.3048)
			(stroke
				(width 0.1)
				(type default)
			)
			(layer "F.Fab")
		)
		(fp_line
			(start -0.12065 0.2794)
			(end -0.12065 0.3048)
			(stroke
				(width 0.1)
				(type default)
			)
			(layer "F.Fab")
		)
		(fp_line
			(start -0.12065 -0.2794)
			(end 0.12065 -0.2794)
			(stroke
				(width 0.1)
				(type default)
			)
			(layer "F.Fab")
		)
		(fp_line
			(start -0.12065 -0.305054)
			(end -0.12065 -0.2794)
			(stroke
				(width 0.1)
				(type default)
			)
			(layer "F.Fab")
		)
		(fp_line
			(start -0.67945 0.3048)
			(end -0.67945 -0.305054)
			(stroke
				(width 0.1)
				(type default)
			)
			(layer "F.Fab")
		)
		(fp_line
			(start -0.67945 -0.305054)
			(end -0.12065 -0.305054)
			(stroke
				(width 0.1)
				(type default)
			)
			(layer "F.Fab")
		)
		(pad "1" smd circle
			(at -0.40005 0 180)
			(size 0 0)
			(layers "F.Cu" "F.Mask" "F.Paste")
			(net "GPU_3V3IO_RSVD3_ISO")
		)
		(pad "2" smd circle
			(at 0.40005 0 180)
			(size 0 0)
			(layers "F.Cu" "F.Mask" "F.Paste")
			(net "GND")
		)
	)
	(footprint ""
		(layer "F.Cu")
		(at 459.437486 -93.627448)
		(property "Reference" "U224"
			(at -1.651 -1.793748 0)
			(unlocked yes)
			(layer "F.SilkS")
			(effects
				(font
					(size 0.7874 0.5842)
					(thickness 0.1524)
				)
				(justify left)
			)
		)
		(property "Value" ""
			(at 0 0 0)
			(layer "F.Fab")
			(effects
				(font
					(size 1.27 1.27)
				)
			)
		)
		(duplicate_pad_numbers_are_jumpers no)
		(fp_line
			(start -1.400048 1.100074)
			(end -1.400048 -1.100074)
			(stroke
				(width 0.1524)
				(type default)
			)
			(layer "F.SilkS")
		)
		(fp_line
			(start 1.400048 -1.100074)
			(end -1.400048 -1.100074)
			(stroke
				(width 0.1524)
				(type default)
			)
			(layer "F.SilkS")
		)
		(fp_line
			(start 1.400048 -1.100074)
			(end 1.400048 1.100074)
			(stroke
				(width 0.1524)
				(type default)
			)
			(layer "F.SilkS")
		)
		(fp_line
			(start 1.400048 1.100074)
			(end -1.400048 1.100074)
			(stroke
				(width 0.1524)
				(type default)
			)
			(layer "F.SilkS")
		)
		(fp_poly
			(pts
				(xy -1.590548 -0.649986) (xy -2.606548 -0.141986) (xy -2.606548 -1.157986)
			)
			(stroke
				(width 0)
				(type default)
			)
			(fill yes)
			(layer "F.SilkS")
		)
		(fp_line
			(start -0.674878 -1.100074)
			(end 0.674878 -1.100074)
			(stroke
				(width 0.1)
				(type default)
			)
			(layer "F.Fab")
		)
		(fp_line
			(start -0.674878 1.100074)
			(end -0.674878 -1.100074)
			(stroke
				(width 0.1)
				(type default)
			)
			(layer "F.Fab")
		)
		(fp_line
			(start 0.674878 -1.100074)
			(end 0.674878 1.100074)
			(stroke
				(width 0.1)
				(type default)
			)
			(layer "F.Fab")
		)
		(fp_line
			(start 0.674878 1.100074)
			(end -0.674878 1.100074)
			(stroke
				(width 0.1)
				(type default)
			)
			(layer "F.Fab")
		)
		(fp_poly
			(pts
				(xy -1.590548 -0.649986) (xy -2.606548 -1.157986) (xy -2.606548 -0.141986)
			)
			(stroke
				(width 0)
				(type default)
			)
			(fill yes)
			(layer "F.Fab")
		)
		(pad "1" smd rect
			(at -0.94996 -0.649986 270)
			(size 0.4318 0.6096)
			(layers "F.Cu" "F.Mask" "F.Paste")
			(net "OCP_SFF_AUX_PWR_EN_R4")
		)
		(pad "2" smd rect
			(at -0.94996 0 270)
			(size 0.4318 0.6096)
			(layers "F.Cu" "F.Mask" "F.Paste")
			(net "RST_SMB_SWITCH_N")
		)
		(pad "3" smd rect
			(at -0.94996 0.649986 270)
			(size 0.4318 0.6096)
			(layers "F.Cu" "F.Mask" "F.Paste")
			(net "GND")
		)
		(pad "4" smd rect
			(at 0.94996 0.649986 270)
			(size 0.4318 0.6096)
			(layers "F.Cu" "F.Mask" "F.Paste")
			(net "RST_HP_OCP_SFF_R_N")
		)
		(pad "5" smd rect
			(at 0.94996 -0.649986 270)
			(size 0.4318 0.6096)
			(layers "F.Cu" "F.Mask" "F.Paste")
			(net "P3V3_AUX")
		)
	)
)
